# T6G (Grand Teton) — schematic netlist excerpt (pin names and nets, part order shuffled) for the footprints in the layout excerpt that follows; sources: Cadence DE-HDL packaged netlist, KiCad conversion of 04192023_DAF0TMB3IC0_F0TG_MB_C_brd_V02_OCP.brd

C1866  Q_CAP  0.1UF 25V 10% X7R  pkg 0402  page 111 : A = P3V3_AUX ; B = GND
R1572  Q_RES  49.9 1% CHIP  pkg 0402LF  page 90 : A = I3C_SPD_DDRAF_CPU0_SCL ; B = I3C_SPD_DDRE_CPU0_SCL

(kicad_pcb
	(version 20260206)
	(generator "pcbnew")
	(generator_version "10.0")
	(general
		(thickness 1.6)
		(legacy_teardrops no)
	)
	(paper "A4")
	(title_block
		(title "04192023_DAF0TMB3IC0_F0TG_MB_C_brd_V02_OCP.brd")
		(comment 1 "Grand Teton / footprints 4969-4970 of 8354")
	)
	(layers
		(0 "F.Cu" signal "TOP")
		(4 "In1.Cu" signal "GND")
		(6 "In2.Cu" signal "IN1")
		(8 "In3.Cu" signal "GND1")
		(10 "In4.Cu" signal "IN2")
		(12 "In5.Cu" signal "GND2")
		(14 "In6.Cu" signal "IN3")
		(16 "In7.Cu" signal "GND3")
		(18 "In8.Cu" signal "VCC")
		(20 "In9.Cu" signal "VCC1")
		(22 "In10.Cu" signal "GND4")
		(24 "In11.Cu" signal "IN4")
		(26 "In12.Cu" signal "GND5")
		(28 "In13.Cu" signal "IN5")
		(30 "In14.Cu" signal "GND6")
		(32 "In15.Cu" signal "IN6")
		(34 "In16.Cu" signal "GND7")
		(2 "B.Cu" signal "BOTTOM")
		(9 "F.Adhes" user "F.Adhesive")
		(11 "B.Adhes" user "B.Adhesive")
		(13 "F.Paste" user "Package Geometry/Pastemask Top")
		(15 "B.Paste" user "Package Geometry/Pastemask Bottom")
		(5 "F.SilkS" user "Ref Des/Silkscreen Top")
		(7 "B.SilkS" user "Ref Des/Silkscreen Bottom")
		(1 "F.Mask" user "Board Geometry/Soldermask Top")
		(3 "B.Mask" user "Board Geometry/Soldermask Bottom")
		(17 "Dwgs.User" user "User.Drawings")
		(19 "Cmts.User" user "User.Comments")
		(21 "Eco1.User" user "User.Eco1")
		(23 "Eco2.User" user "User.Eco2")
		(25 "Edge.Cuts" user "Board Geometry/Outline")
		(27 "Margin" user)
		(31 "F.CrtYd" user "Package Geometry/Place Bound Top")
		(29 "B.CrtYd" user "Package Geometry/Place Bound Bottom")
		(35 "F.Fab" user "Ref Des/Assembly Top")
		(33 "B.Fab" user "Ref Des/Assembly Bottom")
	)
	(footprint ""
		(layer "B.Cu")
		(at 276.436582 -194.893946 180)
		(property "Reference" "R1572"
			(at 0 0 0)
			(layer "B.SilkS")
			(hide yes)
			(effects
				(font
					(size 1.27 1.27)
				)
				(justify mirror)
			)
		)
		(property "Value" ""
			(at 0 0 0)
			(layer "B.Fab")
			(effects
				(font
					(size 1.27 1.27)
				)
				(justify mirror)
			)
		)
		(duplicate_pad_numbers_are_jumpers no)
		(fp_line
			(start 0.7874 0.4064)
			(end 0.7874 -0.4064)
			(stroke
				(width 0.1524)
				(type default)
			)
			(layer "B.SilkS")
		)
		(fp_line
			(start 0.7874 -0.4064)
			(end -0.7874 -0.4064)
			(stroke
				(width 0.1524)
				(type default)
			)
			(layer "B.SilkS")
		)
		(fp_line
			(start -0.7874 0.4064)
			(end 0.7874 0.4064)
			(stroke
				(width 0.1524)
				(type default)
			)
			(layer "B.SilkS")
		)
		(fp_line
			(start -0.7874 -0.4064)
			(end -0.7874 0.4064)
			(stroke
				(width 0.1524)
				(type default)
			)
			(layer "B.SilkS")
		)
		(fp_line
			(start 0.67945 0.3048)
			(end 0.67945 -0.305054)
			(stroke
				(width 0.1)
				(type default)
			)
			(layer "B.Fab")
		)
		(fp_line
			(start 0.67945 -0.305054)
			(end 0.12065 -0.305054)
			(stroke
				(width 0.1)
				(type default)
			)
			(layer "B.Fab")
		)
		(fp_line
			(start 0.12065 0.3048)
			(end 0.67945 0.3048)
			(stroke
				(width 0.1)
				(type default)
			)
			(layer "B.Fab")
		)
		(fp_line
			(start 0.12065 0.2794)
			(end 0.12065 0.3048)
			(stroke
				(width 0.1)
				(type default)
			)
			(layer "B.Fab")
		)
		(fp_line
			(start 0.12065 -0.2794)
			(end -0.12065 -0.2794)
			(stroke
				(width 0.1)
				(type default)
			)
			(layer "B.Fab")
		)
		(fp_line
			(start 0.12065 -0.305054)
			(end 0.12065 -0.2794)
			(stroke
				(width 0.1)
				(type default)
			)
			(layer "B.Fab")
		)
		(fp_line
			(start -0.120396 0.3048)
			(end -0.120396 0.2794)
			(stroke
				(width 0.1)
				(type default)
			)
			(layer "B.Fab")
		)
		(fp_line
			(start -0.120396 0.2794)
			(end 0.12065 0.2794)
			(stroke
				(width 0.1)
				(type default)
			)
			(layer "B.Fab")
		)
		(fp_line
			(start -0.12065 -0.2794)
			(end -0.12065 -0.3048)
			(stroke
				(width 0.1)
				(type default)
			)
			(layer "B.Fab")
		)
		(fp_line
			(start -0.12065 -0.3048)
			(end -0.67945 -0.3048)
			(stroke
				(width 0.1)
				(type default)
			)
			(layer "B.Fab")
		)
		(fp_line
			(start -0.67945 0.3048)
			(end -0.120396 0.3048)
			(stroke
				(width 0.1)
				(type default)
			)
			(layer "B.Fab")
		)
		(fp_line
			(start -0.67945 -0.3048)
			(end -0.67945 0.3048)
			(stroke
				(width 0.1)
				(type default)
			)
			(layer "B.Fab")
		)
		(pad "1" smd circle
			(at 0.40005 0)
			(size 0 0)
			(layers "B.Cu" "B.Mask" "B.Paste")
			(net "I3C_SPD_DDRAF_CPU0_SCL")
		)
		(pad "2" smd circle
			(at -0.40005 0)
			(size 0 0)
			(layers "B.Cu" "B.Mask" "B.Paste")
			(net "I3C_SPD_DDRE_CPU0_SCL")
		)
	)
	(footprint ""
		(layer "B.Cu")
		(at 33.44545 -426.850302 180)
		(property "Reference" "C1866"
			(at 0 0 0)
			(layer "B.SilkS")
			(hide yes)
			(effects
				(font
					(size 1.27 1.27)
				)
				(justify mirror)
			)
		)
		(property "Value" ""
			(at 0 0 0)
			(layer "B.Fab")
			(effects
				(font
					(size 1.27 1.27)
				)
				(justify mirror)
			)
		)
		(duplicate_pad_numbers_are_jumpers no)
		(fp_line
			(start 0.7874 0.4064)
			(end 0.7874 -0.4064)
			(stroke
				(width 0.1524)
				(type default)
			)
			(layer "B.SilkS")
		)
		(fp_line
			(start 0.7874 -0.4064)
			(end -0.7874 -0.4064)
			(stroke
				(width 0.1524)
				(type default)
			)
			(layer "B.SilkS")
		)
		(fp_line
			(start -0.7874 0.4064)
			(end 0.7874 0.4064)
			(stroke
				(width 0.1524)
				(type default)
			)
			(layer "B.SilkS")
		)
		(fp_line
			(start -0.7874 -0.4064)
			(end -0.7874 0.4064)
			(stroke
				(width 0.1524)
				(type default)
			)
			(layer "B.SilkS")
		)
		(fp_line
			(start 0.67945 0.3048)
			(end 0.67945 -0.305054)
			(stroke
				(width 0.1)
				(type default)
			)
			(layer "B.Fab")
		)
		(fp_line
			(start 0.67945 -0.305054)
			(end 0.12065 -0.305054)
			(stroke
				(width 0.1)
				(type default)
			)
			(layer "B.Fab")
		)
		(fp_line
			(start 0.12065 0.3048)
			(end 0.67945 0.3048)
			(stroke
				(width 0.1)
				(type default)
			)
			(layer "B.Fab")
		)
		(fp_line
			(start 0.12065 0.2794)
			(end 0.12065 0.3048)
			(stroke
				(width 0.1)
				(type default)
			)
			(layer "B.Fab")
		)
		(fp_line
			(start 0.12065 -0.2794)
			(end -0.12065 -0.2794)
			(stroke
				(width 0.1)
				(type default)
			)
			(layer "B.Fab")
		)
		(fp_line
			(start 0.12065 -0.305054)
			(end 0.12065 -0.2794)
			(stroke
				(width 0.1)
				(type default)
			)
			(layer "B.Fab")
		)
		(fp_line
			(start -0.120396 0.3048)
			(end -0.120396 0.2794)
			(stroke
				(width 0.1)
				(type default)
			)
			(layer "B.Fab")
		)
		(fp_line
			(start -0.120396 0.2794)
			(end 0.12065 0.2794)
			(stroke
				(width 0.1)
				(type default)
			)
			(layer "B.Fab")
		)
		(fp_line
			(start -0.12065 -0.2794)
			(end -0.12065 -0.3048)
			(stroke
				(width 0.1)
				(type default)
			)
			(layer "B.Fab")
		)
		(fp_line
			(start -0.12065 -0.3048)
			(end -0.67945 -0.3048)
			(stroke
				(width 0.1)
				(type default)
			)
			(layer "B.Fab")
		)
		(fp_line
			(start -0.67945 0.3048)
			(end -0.120396 0.3048)
			(stroke
				(width 0.1)
				(type default)
			)
			(layer "B.Fab")
		)
		(fp_line
			(start -0.67945 -0.3048)
			(end -0.67945 0.3048)
			(stroke
				(width 0.1)
				(type default)
			)
			(layer "B.Fab")
		)
		(pad "1" smd circle
			(at 0.40005 0)
			(size 0 0)
			(layers "B.Cu" "B.Mask" "B.Paste")
			(net "P3V3_AUX")
		)
		(pad "2" smd circle
			(at -0.40005 0)
			(size 0 0)
			(layers "B.Cu" "B.Mask" "B.Paste")
			(net "GND")
		)
	)
)
